# BASEBOARD_FAB2 (Tioga Pass) — schematic netlist excerpt (pin names and nets, part order shuffled) for the footprints in the layout excerpt that follows; sources: Cadence DE-HDL packaged netlist, KiCad conversion of Wiwynn_Tioga_Pass_MB.brd

U7E1  PCA9617  IC  pkg SSOP  page 99
  VCCA  = PVCCIO_CPU0
  SCLA  = SMB_DDR_DEF_SCL_G
  SDAA  = SMB_DDR_DEF_SDA_G
  EN  = TP_SMB_DDR_DEF_EN
  SDAB  = SMB_DDR_DEF_VPP_SDA_R
  SCLB  = SMB_DDR_DEF_VPP_SCL_R
  VCCB  = PVPP_DEF

R2L5  RES  2.0K 1% CHIP  pkg 0402  page 178 : A = P3V3_STBY ; B = SGPIO_PCH_SSATA_LOAD_R
R1M24  RES  10.0K 1% CHIP  pkg 0402  page 176 : A = P3V3_STBY ; B = FM_OC0_USB_N

(kicad_pcb
	(version 20260206)
	(generator "pcbnew")
	(generator_version "10.0")
	(general
		(thickness 1.6)
		(legacy_teardrops no)
	)
	(paper "A4")
	(title_block
		(title "Wiwynn_Tioga_Pass_MB.brd")
		(comment 1 "Tioga Pass / footprints 2452-2454 of 4770")
	)
	(layers
		(0 "F.Cu" signal "TOP")
		(4 "In1.Cu" signal "L2GND")
		(6 "In2.Cu" signal "L3")
		(8 "In3.Cu" signal "L4GND")
		(10 "In4.Cu" signal "L5")
		(12 "In5.Cu" signal "L6GND")
		(14 "In6.Cu" signal "L7VCC")
		(16 "In7.Cu" signal "L8VCC")
		(18 "In8.Cu" signal "L9GND")
		(20 "In9.Cu" signal "L10")
		(22 "In10.Cu" signal "L11GND")
		(24 "In11.Cu" signal "L12")
		(26 "In12.Cu" signal "L13GND")
		(2 "B.Cu" signal "BOTTOM")
		(9 "F.Adhes" user "F.Adhesive")
		(11 "B.Adhes" user "B.Adhesive")
		(13 "F.Paste" user "Package Geometry/Pastemask Top")
		(15 "B.Paste" user "Package Geometry/Pastemask Bottom")
		(5 "F.SilkS" user "Ref Des/Silkscreen Top")
		(7 "B.SilkS" user "Ref Des/Silkscreen Bottom")
		(1 "F.Mask" user "Board Geometry/Soldermask Top")
		(3 "B.Mask" user "Board Geometry/Soldermask Bottom")
		(17 "Dwgs.User" user "User.Drawings")
		(19 "Cmts.User" user "User.Comments")
		(21 "Eco1.User" user "User.Eco1")
		(23 "Eco2.User" user "User.Eco2")
		(25 "Edge.Cuts" user "Board Geometry/Outline")
		(27 "Margin" user)
		(31 "F.CrtYd" user "Package Geometry/Place Bound Top")
		(29 "B.CrtYd" user "Package Geometry/Place Bound Bottom")
		(35 "F.Fab" user "Ref Des/Assembly Top")
		(33 "B.Fab" user "Ref Des/Assembly Bottom")
	)
	(footprint ""
		(layer "B.Cu")
		(at 325.5264 -122.81916)
		(property "Reference" "U7E1"
			(at 0.64262 2.90957 0)
			(unlocked yes)
			(layer "B.SilkS")
			(effects
				(font
					(size 0.7874 0.5842)
					(thickness 0.1524)
				)
				(justify mirror)
			)
		)
		(property "Value" ""
			(at 0 0 0)
			(layer "B.Fab")
			(effects
				(font
					(size 1.27 1.27)
				)
				(justify mirror)
			)
		)
		(duplicate_pad_numbers_are_jumpers no)
		(fp_line
			(start -3.225292 -0.57404)
			(end -1.352804 -0.57404)
			(stroke
				(width 0.1524)
				(type default)
			)
			(layer "B.SilkS")
		)
		(fp_line
			(start -3.225038 2.52476)
			(end -1.348486 2.52476)
			(stroke
				(width 0.1524)
				(type default)
			)
			(layer "B.SilkS")
		)
		(fp_circle
			(center 1.454404 -0.556514)
			(end 1.581404 -0.556514)
			(stroke
				(width 0.254)
				(type default)
			)
			(fill no)
			(layer "B.SilkS")
		)
		(fp_poly
			(pts
				(xy -0.7366 -0.57404) (xy -3.8354 -0.57404) (xy -3.8354 2.52476) (xy -0.7366 2.52476)
			)
			(stroke
				(width 0)
				(type default)
			)
			(fill no)
			(layer "B.CrtYd")
		)
		(fp_line
			(start -3.8354 -0.57404)
			(end -3.8354 2.52476)
			(stroke
				(width 0.1)
				(type default)
			)
			(layer "B.Fab")
		)
		(fp_line
			(start -3.8354 2.52476)
			(end -0.7366 2.52476)
			(stroke
				(width 0.1)
				(type default)
			)
			(layer "B.Fab")
		)
		(fp_line
			(start -0.7366 -0.57404)
			(end -3.8354 -0.57404)
			(stroke
				(width 0.1)
				(type default)
			)
			(layer "B.Fab")
		)
		(fp_line
			(start -0.7366 2.52476)
			(end -0.7366 -0.57404)
			(stroke
				(width 0.1)
				(type default)
			)
			(layer "B.Fab")
		)
		(fp_circle
			(center 1.454404 -0.556514)
			(end 1.581404 -0.556514)
			(stroke
				(width 0.254)
				(type default)
			)
			(fill no)
			(layer "B.Fab")
		)
		(pad "1" smd rect
			(at 0 0 180)
			(size 1.778 0.4572)
			(layers "B.Cu" "B.Mask" "B.Paste")
			(net "PVCCIO_CPU0")
		)
		(pad "2" smd rect
			(at 0 0.65024 180)
			(size 1.778 0.4572)
			(layers "B.Cu" "B.Mask" "B.Paste")
			(net "SMB_DDR_DEF_SCL_G")
		)
		(pad "3" smd rect
			(at 0 1.30048 180)
			(size 1.778 0.4572)
			(layers "B.Cu" "B.Mask" "B.Paste")
			(net "SMB_DDR_DEF_SDA_G")
		)
		(pad "4" smd rect
			(at 0 1.95072 180)
			(size 1.778 0.4572)
			(layers "B.Cu" "B.Mask" "B.Paste")
			(net "GND")
		)
		(pad "5" smd rect
			(at -4.572 1.95072 180)
			(size 1.778 0.4572)
			(layers "B.Cu" "B.Mask" "B.Paste")
			(net "TP_SMB_DDR_DEF_EN")
		)
		(pad "6" smd rect
			(at -4.572 1.30048 180)
			(size 1.778 0.4572)
			(layers "B.Cu" "B.Mask" "B.Paste")
			(net "SMB_DDR_DEF_VPP_SDA_R")
		)
		(pad "7" smd rect
			(at -4.572 0.65024 180)
			(size 1.778 0.4572)
			(layers "B.Cu" "B.Mask" "B.Paste")
			(net "SMB_DDR_DEF_VPP_SCL_R")
		)
		(pad "8" smd rect
			(at -4.572 0 180)
			(size 1.778 0.4572)
			(layers "B.Cu" "B.Mask" "B.Paste")
			(net "PVPP_DEF")
		)
	)
	(footprint ""
		(layer "B.Cu")
		(at 390.906 -84.709 180)
		(property "Reference" "R2L5"
			(at 0 0 0)
			(layer "B.SilkS")
			(hide yes)
			(effects
				(font
					(size 1.27 1.27)
				)
				(justify mirror)
			)
		)
		(property "Value" ""
			(at 0 0 0)
			(layer "B.Fab")
			(effects
				(font
					(size 1.27 1.27)
				)
				(justify mirror)
			)
		)
		(duplicate_pad_numbers_are_jumpers no)
		(fp_poly
			(pts
				(xy 0.2794 -0.1016) (xy -0.2794 -0.1016) (xy -0.2794 0.9906) (xy 0.2794 0.9906)
			)
			(stroke
				(width 0)
				(type default)
			)
			(fill no)
			(layer "B.CrtYd")
		)
		(fp_line
			(start 0.2794 0.9906)
			(end -0.2794 0.9906)
			(stroke
				(width 0.1)
				(type default)
			)
			(layer "B.Fab")
		)
		(fp_line
			(start 0.2794 -0.1016)
			(end 0.2794 0.9906)
			(stroke
				(width 0.1)
				(type default)
			)
			(layer "B.Fab")
		)
		(fp_line
			(start -0.2794 0.9906)
			(end -0.2794 -0.1016)
			(stroke
				(width 0.1)
				(type default)
			)
			(layer "B.Fab")
		)
		(fp_line
			(start -0.2794 -0.1016)
			(end 0.2794 -0.1016)
			(stroke
				(width 0.1)
				(type default)
			)
			(layer "B.Fab")
		)
		(pad "1" smd rect
			(at 0 0)
			(size 0.508 0.508)
			(layers "B.Cu" "B.Mask" "B.Paste")
			(net "P3V3_STBY")
		)
		(pad "2" smd rect
			(at 0 0.889)
			(size 0.508 0.508)
			(layers "B.Cu" "B.Mask" "B.Paste")
			(net "SGPIO_PCH_SSATA_LOAD_R")
		)
		(zone
			(layer "B.Cu")
			(hatch none 0.5)
			(connect_pads
				(clearance 0)
			)
			(min_thickness 0.25)
			(keepout
				(tracks not_allowed)
				(vias allowed)
				(pads allowed)
				(copperpour not_allowed)
				(footprints allowed)
			)
			(placement
				(enabled no)
				(sheetname "")
			)
			(fill
				(thermal_gap 0.5)
				(thermal_bridge_width 0.5)
				(island_removal_mode 0)
			)
			(polygon
				(pts
					(xy 390.652 -85.344) (xy 391.16 -85.344) (xy 391.16 -84.963) (xy 390.652 -84.963)
				)
			)
		)
		(zone
			(layer "B.Cu")
			(hatch none 0.5)
			(connect_pads
				(clearance 0)
			)
			(min_thickness 0.25)
			(keepout
				(tracks allowed)
				(vias not_allowed)
				(pads allowed)
				(copperpour not_allowed)
				(footprints allowed)
			)
			(placement
				(enabled no)
				(sheetname "")
			)
			(fill
				(thermal_gap 0.5)
				(thermal_bridge_width 0.5)
				(island_removal_mode 0)
			)
			(polygon
				(pts
					(xy 390.652 -84.963) (xy 391.16 -84.963) (xy 391.16 -85.344) (xy 390.652 -85.344)
				)
			)
		)
	)
	(footprint ""
		(layer "B.Cu")
		(at 463.55 -127.9398 180)
		(property "Reference" "R1M24"
			(at 0 0 0)
			(layer "B.SilkS")
			(hide yes)
			(effects
				(font
					(size 1.27 1.27)
				)
				(justify mirror)
			)
		)
		(property "Value" ""
			(at 0 0 0)
			(layer "B.Fab")
			(effects
				(font
					(size 1.27 1.27)
				)
				(justify mirror)
			)
		)
		(duplicate_pad_numbers_are_jumpers no)
		(fp_poly
			(pts
				(xy 0.2794 -0.1016) (xy -0.2794 -0.1016) (xy -0.2794 0.9906) (xy 0.2794 0.9906)
			)
			(stroke
				(width 0)
				(type default)
			)
			(fill no)
			(layer "B.CrtYd")
		)
		(fp_line
			(start 0.2794 0.9906)
			(end -0.2794 0.9906)
			(stroke
				(width 0.1)
				(type default)
			)
			(layer "B.Fab")
		)
		(fp_line
			(start 0.2794 -0.1016)
			(end 0.2794 0.9906)
			(stroke
				(width 0.1)
				(type default)
			)
			(layer "B.Fab")
		)
		(fp_line
			(start -0.2794 0.9906)
			(end -0.2794 -0.1016)
			(stroke
				(width 0.1)
				(type default)
			)
			(layer "B.Fab")
		)
		(fp_line
			(start -0.2794 -0.1016)
			(end 0.2794 -0.1016)
			(stroke
				(width 0.1)
				(type default)
			)
			(layer "B.Fab")
		)
		(pad "1" smd rect
			(at 0 0)
			(size 0.508 0.508)
			(layers "B.Cu" "B.Mask" "B.Paste")
			(net "P3V3_STBY")
		)
		(pad "2" smd rect
			(at 0 0.889)
			(size 0.508 0.508)
			(layers "B.Cu" "B.Mask" "B.Paste")
			(net "FM_OC0_USB_N")
		)
		(zone
			(layer "B.Cu")
			(hatch none 0.5)
			(connect_pads
				(clearance 0)
			)
			(min_thickness 0.25)
			(keepout
				(tracks not_allowed)
				(vias allowed)
				(pads allowed)
				(copperpour not_allowed)
				(footprints allowed)
			)
			(placement
				(enabled no)
				(sheetname "")
			)
			(fill
				(thermal_gap 0.5)
				(thermal_bridge_width 0.5)
				(island_removal_mode 0)
			)
			(polygon
				(pts
					(xy 463.296 -128.5748) (xy 463.804 -128.5748) (xy 463.804 -128.1938) (xy 463.296 -128.1938)
				)
			)
		)
		(zone
			(layer "B.Cu")
			(hatch none 0.5)
			(connect_pads
				(clearance 0)
			)
			(min_thickness 0.25)
			(keepout
				(tracks allowed)
				(vias not_allowed)
				(pads allowed)
				(copperpour not_allowed)
				(footprints allowed)
			)
			(placement
				(enabled no)
				(sheetname "")
			)
			(fill
				(thermal_gap 0.5)
				(thermal_bridge_width 0.5)
				(island_removal_mode 0)
			)
			(polygon
				(pts
					(xy 463.296 -128.1938) (xy 463.804 -128.1938) (xy 463.804 -128.5748) (xy 463.296 -128.5748)
				)
			)
		)
	)
)
